(kicad_pcb
	(version 20260206)
	(generator "pcbnew")
	(generator_version "10.0")
	(general
		(thickness 1.6)
		(legacy_teardrops no)
	)
	(paper "A4")
	(title_block
		(title "04192023_DAF0TMB3IC0_F0TG_MB_C_brd_V02_OCP.brd")
		(comment 1 "Grand Teton / footprints 8170-8175 of 8354")
	)
	(layers
		(0 "F.Cu" signal "TOP")
		(4 "In1.Cu" signal "GND")
		(6 "In2.Cu" signal "IN1")
		(8 "In3.Cu" signal "GND1")
		(10 "In4.Cu" signal "IN2")
		(12 "In5.Cu" signal "GND2")
		(14 "In6.Cu" signal "IN3")
		(16 "In7.Cu" signal "GND3")
		(18 "In8.Cu" signal "VCC")
		(20 "In9.Cu" signal "VCC1")
		(22 "In10.Cu" signal "GND4")
		(24 "In11.Cu" signal "IN4")
		(26 "In12.Cu" signal "GND5")
		(28 "In13.Cu" signal "IN5")
		(30 "In14.Cu" signal "GND6")
		(32 "In15.Cu" signal "IN6")
		(34 "In16.Cu" signal "GND7")
		(2 "B.Cu" signal "BOTTOM")
		(9 "F.Adhes" user "F.Adhesive")
		(11 "B.Adhes" user "B.Adhesive")
		(13 "F.Paste" user "Package Geometry/Pastemask Top")
		(15 "B.Paste" user "Package Geometry/Pastemask Bottom")
		(5 "F.SilkS" user "Ref Des/Silkscreen Top")
		(7 "B.SilkS" user "Ref Des/Silkscreen Bottom")
		(1 "F.Mask" user "Board Geometry/Soldermask Top")
		(3 "B.Mask" user "Board Geometry/Soldermask Bottom")
		(17 "Dwgs.User" user "User.Drawings")
		(19 "Cmts.User" user "User.Comments")
		(21 "Eco1.User" user "User.Eco1")
		(23 "Eco2.User" user "User.Eco2")
		(25 "Edge.Cuts" user "Board Geometry/Outline")
		(27 "Margin" user)
		(31 "F.CrtYd" user "Package Geometry/Place Bound Top")
		(29 "B.CrtYd" user "Package Geometry/Place Bound Bottom")
		(35 "F.Fab" user "Ref Des/Assembly Top")
		(33 "B.Fab" user "Ref Des/Assembly Bottom")
	)
	(footprint ""
		(layer "B.Cu")
		(at 353.900232 -256.505202 180)
		(property "Reference" "C2163"
			(at 0 0 0)
			(layer "B.SilkS")
			(hide yes)
			(effects
				(font
					(size 1.27 1.27)
				)
				(justify mirror)
			)
		)
		(property "Value" ""
			(at 0 0 0)
			(layer "B.Fab")
			(effects
				(font
					(size 1.27 1.27)
				)
				(justify mirror)
			)
		)
		(duplicate_pad_numbers_are_jumpers no)
		(fp_line
			(start 0.7874 0.4064)
			(end 0.7874 -0.4064)
			(stroke
				(width 0.1524)
				(type default)
			)
			(layer "B.SilkS")
		)
		(fp_line
			(start 0.7874 -0.4064)
			(end -0.7874 -0.4064)
			(stroke
				(width 0.1524)
				(type default)
			)
			(layer "B.SilkS")
		)
		(fp_line
			(start -0.7874 0.4064)
			(end 0.7874 0.4064)
			(stroke
				(width 0.1524)
				(type default)
			)
			(layer "B.SilkS")
		)
		(fp_line
			(start -0.7874 -0.4064)
			(end -0.7874 0.4064)
			(stroke
				(width 0.1524)
				(type default)
			)
			(layer "B.SilkS")
		)
		(fp_line
			(start 0.67945 0.3048)
			(end 0.67945 -0.305054)
			(stroke
				(width 0.1)
				(type default)
			)
			(layer "B.Fab")
		)
		(fp_line
			(start 0.67945 -0.305054)
			(end 0.12065 -0.305054)
			(stroke
				(width 0.1)
				(type default)
			)
			(layer "B.Fab")
		)
		(fp_line
			(start 0.12065 0.3048)
			(end 0.67945 0.3048)
			(stroke
				(width 0.1)
				(type default)
			)
			(layer "B.Fab")
		)
		(fp_line
			(start 0.12065 0.2794)
			(end 0.12065 0.3048)
			(stroke
				(width 0.1)
				(type default)
			)
			(layer "B.Fab")
		)
		(fp_line
			(start 0.12065 -0.2794)
			(end -0.12065 -0.2794)
			(stroke
				(width 0.1)
				(type default)
			)
			(layer "B.Fab")
		)
		(fp_line
			(start 0.12065 -0.305054)
			(end 0.12065 -0.2794)
			(stroke
				(width 0.1)
				(type default)
			)
			(layer "B.Fab")
		)
		(fp_line
			(start -0.120396 0.3048)
			(end -0.120396 0.2794)
			(stroke
				(width 0.1)
				(type default)
			)
			(layer "B.Fab")
		)
		(fp_line
			(start -0.120396 0.2794)
			(end 0.12065 0.2794)
			(stroke
				(width 0.1)
				(type default)
			)
			(layer "B.Fab")
		)
		(fp_line
			(start -0.12065 -0.2794)
			(end -0.12065 -0.3048)
			(stroke
				(width 0.1)
				(type default)
			)
			(layer "B.Fab")
		)
		(fp_line
			(start -0.12065 -0.3048)
			(end -0.67945 -0.3048)
			(stroke
				(width 0.1)
				(type default)
			)
			(layer "B.Fab")
		)
		(fp_line
			(start -0.67945 0.3048)
			(end -0.120396 0.3048)
			(stroke
				(width 0.1)
				(type default)
			)
			(layer "B.Fab")
		)
		(fp_line
			(start -0.67945 -0.3048)
			(end -0.67945 0.3048)
			(stroke
				(width 0.1)
				(type default)
			)
			(layer "B.Fab")
		)
		(pad "1" smd circle
			(at 0.40005 0)
			(size 0 0)
			(layers "B.Cu" "B.Mask" "B.Paste")
			(net "PVDD18_S5_P0")
		)
		(pad "2" smd circle
			(at -0.40005 0)
			(size 0 0)
			(layers "B.Cu" "B.Mask" "B.Paste")
			(net "GND")
		)
	)
	(footprint ""
		(layer "B.Cu")
		(at 351.612454 -262.70331 180)
		(property "Reference" "C2533"
			(at 0 0 0)
			(layer "B.SilkS")
			(hide yes)
			(effects
				(font
					(size 1.27 1.27)
				)
				(justify mirror)
			)
		)
		(property "Value" ""
			(at 0 0 0)
			(layer "B.Fab")
			(effects
				(font
					(size 1.27 1.27)
				)
				(justify mirror)
			)
		)
		(duplicate_pad_numbers_are_jumpers no)
		(fp_line
			(start 0.7874 0.4064)
			(end 0.7874 -0.4064)
			(stroke
				(width 0.1524)
				(type default)
			)
			(layer "B.SilkS")
		)
		(fp_line
			(start 0.7874 -0.4064)
			(end -0.7874 -0.4064)
			(stroke
				(width 0.1524)
				(type default)
			)
			(layer "B.SilkS")
		)
		(fp_line
			(start -0.7874 0.4064)
			(end 0.7874 0.4064)
			(stroke
				(width 0.1524)
				(type default)
			)
			(layer "B.SilkS")
		)
		(fp_line
			(start -0.7874 -0.4064)
			(end -0.7874 0.4064)
			(stroke
				(width 0.1524)
				(type default)
			)
			(layer "B.SilkS")
		)
		(fp_line
			(start 0.67945 0.3048)
			(end 0.67945 -0.305054)
			(stroke
				(width 0.1)
				(type default)
			)
			(layer "B.Fab")
		)
		(fp_line
			(start 0.67945 -0.305054)
			(end 0.12065 -0.305054)
			(stroke
				(width 0.1)
				(type default)
			)
			(layer "B.Fab")
		)
		(fp_line
			(start 0.12065 0.3048)
			(end 0.67945 0.3048)
			(stroke
				(width 0.1)
				(type default)
			)
			(layer "B.Fab")
		)
		(fp_line
			(start 0.12065 0.2794)
			(end 0.12065 0.3048)
			(stroke
				(width 0.1)
				(type default)
			)
			(layer "B.Fab")
		)
		(fp_line
			(start 0.12065 -0.2794)
			(end -0.12065 -0.2794)
			(stroke
				(width 0.1)
				(type default)
			)
			(layer "B.Fab")
		)
		(fp_line
			(start 0.12065 -0.305054)
			(end 0.12065 -0.2794)
			(stroke
				(width 0.1)
				(type default)
			)
			(layer "B.Fab")
		)
		(fp_line
			(start -0.120396 0.3048)
			(end -0.120396 0.2794)
			(stroke
				(width 0.1)
				(type default)
			)
			(layer "B.Fab")
		)
		(fp_line
			(start -0.120396 0.2794)
			(end 0.12065 0.2794)
			(stroke
				(width 0.1)
				(type default)
			)
			(layer "B.Fab")
		)
		(fp_line
			(start -0.12065 -0.2794)
			(end -0.12065 -0.3048)
			(stroke
				(width 0.1)
				(type default)
			)
			(layer "B.Fab")
		)
		(fp_line
			(start -0.12065 -0.3048)
			(end -0.67945 -0.3048)
			(stroke
				(width 0.1)
				(type default)
			)
			(layer "B.Fab")
		)
		(fp_line
			(start -0.67945 0.3048)
			(end -0.120396 0.3048)
			(stroke
				(width 0.1)
				(type default)
			)
			(layer "B.Fab")
		)
		(fp_line
			(start -0.67945 -0.3048)
			(end -0.67945 0.3048)
			(stroke
				(width 0.1)
				(type default)
			)
			(layer "B.Fab")
		)
		(pad "1" smd circle
			(at 0.40005 0)
			(size 0 0)
			(layers "B.Cu" "B.Mask" "B.Paste")
			(net "PVDDCR_SOC_P0")
		)
		(pad "2" smd circle
			(at -0.40005 0)
			(size 0 0)
			(layers "B.Cu" "B.Mask" "B.Paste")
			(net "GND")
		)
	)
	(footprint ""
		(layer "B.Cu")
		(at 414.096454 -191.20231)
		(property "Reference" "R95"
			(at 0 0 0)
			(layer "B.SilkS")
			(hide yes)
			(effects
				(font
					(size 1.27 1.27)
				)
				(justify mirror)
			)
		)
		(property "Value" ""
			(at 0 0 0)
			(layer "B.Fab")
			(effects
				(font
					(size 1.27 1.27)
				)
				(justify mirror)
			)
		)
		(duplicate_pad_numbers_are_jumpers no)
		(fp_line
			(start -0.7874 -0.4064)
			(end -0.7874 0.4064)
			(stroke
				(width 0.1524)
				(type default)
			)
			(layer "B.SilkS")
		)
		(fp_line
			(start -0.7874 0.4064)
			(end 0.7874 0.4064)
			(stroke
				(width 0.1524)
				(type default)
			)
			(layer "B.SilkS")
		)
		(fp_line
			(start 0.7874 -0.4064)
			(end -0.7874 -0.4064)
			(stroke
				(width 0.1524)
				(type default)
			)
			(layer "B.SilkS")
		)
		(fp_line
			(start 0.7874 0.4064)
			(end 0.7874 -0.4064)
			(stroke
				(width 0.1524)
				(type default)
			)
			(layer "B.SilkS")
		)
		(fp_line
			(start -0.67945 -0.3048)
			(end -0.67945 0.3048)
			(stroke
				(width 0.1)
				(type default)
			)
			(layer "B.Fab")
		)
		(fp_line
			(start -0.67945 0.3048)
			(end -0.120396 0.3048)
			(stroke
				(width 0.1)
				(type default)
			)
			(layer "B.Fab")
		)
		(fp_line
			(start -0.12065 -0.3048)
			(end -0.67945 -0.3048)
			(stroke
				(width 0.1)
				(type default)
			)
			(layer "B.Fab")
		)
		(fp_line
			(start -0.12065 -0.2794)
			(end -0.12065 -0.3048)
			(stroke
				(width 0.1)
				(type default)
			)
			(layer "B.Fab")
		)
		(fp_line
			(start -0.120396 0.2794)
			(end 0.12065 0.2794)
			(stroke
				(width 0.1)
				(type default)
			)
			(layer "B.Fab")
		)
		(fp_line
			(start -0.120396 0.3048)
			(end -0.120396 0.2794)
			(stroke
				(width 0.1)
				(type default)
			)
			(layer "B.Fab")
		)
		(fp_line
			(start 0.12065 -0.305054)
			(end 0.12065 -0.2794)
			(stroke
				(width 0.1)
				(type default)
			)
			(layer "B.Fab")
		)
		(fp_line
			(start 0.12065 -0.2794)
			(end -0.12065 -0.2794)
			(stroke
				(width 0.1)
				(type default)
			)
			(layer "B.Fab")
		)
		(fp_line
			(start 0.12065 0.2794)
			(end 0.12065 0.3048)
			(stroke
				(width 0.1)
				(type default)
			)
			(layer "B.Fab")
		)
		(fp_line
			(start 0.12065 0.3048)
			(end 0.67945 0.3048)
			(stroke
				(width 0.1)
				(type default)
			)
			(layer "B.Fab")
		)
		(fp_line
			(start 0.67945 -0.305054)
			(end 0.12065 -0.305054)
			(stroke
				(width 0.1)
				(type default)
			)
			(layer "B.Fab")
		)
		(fp_line
			(start 0.67945 0.3048)
			(end 0.67945 -0.305054)
			(stroke
				(width 0.1)
				(type default)
			)
			(layer "B.Fab")
		)
		(pad "1" smd circle
			(at 0.40005 0 180)
			(size 0 0)
			(layers "B.Cu" "B.Mask" "B.Paste")
			(net "P3V3")
		)
		(pad "2" smd circle
			(at -0.40005 0 180)
			(size 0 0)
			(layers "B.Cu" "B.Mask" "B.Paste")
			(net "PWRGD_CHGL_CPU0")
		)
	)
	(footprint ""
		(layer "B.Cu")
		(at 123.611386 -255.845564)
		(property "Reference" "C3918"
			(at 0 0 0)
			(layer "B.SilkS")
			(hide yes)
			(effects
				(font
					(size 1.27 1.27)
				)
				(justify mirror)
			)
		)
		(property "Value" ""
			(at 0 0 0)
			(layer "B.Fab")
			(effects
				(font
					(size 1.27 1.27)
				)
				(justify mirror)
			)
		)
		(duplicate_pad_numbers_are_jumpers no)
		(fp_line
			(start -0.7874 -0.4064)
			(end -0.7874 0.4064)
			(stroke
				(width 0.1524)
				(type default)
			)
			(layer "B.SilkS")
		)
		(fp_line
			(start -0.7874 0.4064)
			(end 0.7874 0.4064)
			(stroke
				(width 0.1524)
				(type default)
			)
			(layer "B.SilkS")
		)
		(fp_line
			(start 0.7874 -0.4064)
			(end -0.7874 -0.4064)
			(stroke
				(width 0.1524)
				(type default)
			)
			(layer "B.SilkS")
		)
		(fp_line
			(start 0.7874 0.4064)
			(end 0.7874 -0.4064)
			(stroke
				(width 0.1524)
				(type default)
			)
			(layer "B.SilkS")
		)
		(fp_line
			(start -0.67945 -0.3048)
			(end -0.67945 0.3048)
			(stroke
				(width 0.1)
				(type default)
			)
			(layer "B.Fab")
		)
		(fp_line
			(start -0.67945 0.3048)
			(end -0.120396 0.3048)
			(stroke
				(width 0.1)
				(type default)
			)
			(layer "B.Fab")
		)
		(fp_line
			(start -0.12065 -0.3048)
			(end -0.67945 -0.3048)
			(stroke
				(width 0.1)
				(type default)
			)
			(layer "B.Fab")
		)
		(fp_line
			(start -0.12065 -0.2794)
			(end -0.12065 -0.3048)
			(stroke
				(width 0.1)
				(type default)
			)
			(layer "B.Fab")
		)
		(fp_line
			(start -0.120396 0.2794)
			(end 0.12065 0.2794)
			(stroke
				(width 0.1)
				(type default)
			)
			(layer "B.Fab")
		)
		(fp_line
			(start -0.120396 0.3048)
			(end -0.120396 0.2794)
			(stroke
				(width 0.1)
				(type default)
			)
			(layer "B.Fab")
		)
		(fp_line
			(start 0.12065 -0.305054)
			(end 0.12065 -0.2794)
			(stroke
				(width 0.1)
				(type default)
			)
			(layer "B.Fab")
		)
		(fp_line
			(start 0.12065 -0.2794)
			(end -0.12065 -0.2794)
			(stroke
				(width 0.1)
				(type default)
			)
			(layer "B.Fab")
		)
		(fp_line
			(start 0.12065 0.2794)
			(end 0.12065 0.3048)
			(stroke
				(width 0.1)
				(type default)
			)
			(layer "B.Fab")
		)
		(fp_line
			(start 0.12065 0.3048)
			(end 0.67945 0.3048)
			(stroke
				(width 0.1)
				(type default)
			)
			(layer "B.Fab")
		)
		(fp_line
			(start 0.67945 -0.305054)
			(end 0.12065 -0.305054)
			(stroke
				(width 0.1)
				(type default)
			)
			(layer "B.Fab")
		)
		(fp_line
			(start 0.67945 0.3048)
			(end 0.67945 -0.305054)
			(stroke
				(width 0.1)
				(type default)
			)
			(layer "B.Fab")
		)
		(pad "1" smd circle
			(at 0.40005 0 180)
			(size 0 0)
			(layers "B.Cu" "B.Mask" "B.Paste")
			(net "PVDDCR_SOC_P1")
		)
		(pad "2" smd circle
			(at -0.40005 0 180)
			(size 0 0)
			(layers "B.Cu" "B.Mask" "B.Paste")
			(net "GND")
		)
	)
	(footprint ""
		(layer "B.Cu")
		(at 22.479 -357.632 180)
		(property "Reference" "PR218"
			(at 0 0 0)
			(layer "B.SilkS")
			(hide yes)
			(effects
				(font
					(size 1.27 1.27)
				)
				(justify mirror)
			)
		)
		(property "Value" ""
			(at 0 0 0)
			(layer "B.Fab")
			(effects
				(font
					(size 1.27 1.27)
				)
				(justify mirror)
			)
		)
		(duplicate_pad_numbers_are_jumpers no)
		(fp_line
			(start 0.7874 0.4064)
			(end 0.7874 -0.4064)
			(stroke
				(width 0.1524)
				(type default)
			)
			(layer "B.SilkS")
		)
		(fp_line
			(start 0.7874 -0.4064)
			(end -0.7874 -0.4064)
			(stroke
				(width 0.1524)
				(type default)
			)
			(layer "B.SilkS")
		)
		(fp_line
			(start -0.7874 0.4064)
			(end 0.7874 0.4064)
			(stroke
				(width 0.1524)
				(type default)
			)
			(layer "B.SilkS")
		)
		(fp_line
			(start -0.7874 -0.4064)
			(end -0.7874 0.4064)
			(stroke
				(width 0.1524)
				(type default)
			)
			(layer "B.SilkS")
		)
		(fp_line
			(start 0.67945 0.3048)
			(end 0.67945 -0.305054)
			(stroke
				(width 0.1)
				(type default)
			)
			(layer "B.Fab")
		)
		(fp_line
			(start 0.67945 -0.305054)
			(end 0.12065 -0.305054)
			(stroke
				(width 0.1)
				(type default)
			)
			(layer "B.Fab")
		)
		(fp_line
			(start 0.12065 0.3048)
			(end 0.67945 0.3048)
			(stroke
				(width 0.1)
				(type default)
			)
			(layer "B.Fab")
		)
		(fp_line
			(start 0.12065 0.2794)
			(end 0.12065 0.3048)
			(stroke
				(width 0.1)
				(type default)
			)
			(layer "B.Fab")
		)
		(fp_line
			(start 0.12065 -0.2794)
			(end -0.12065 -0.2794)
			(stroke
				(width 0.1)
				(type default)
			)
			(layer "B.Fab")
		)
		(fp_line
			(start 0.12065 -0.305054)
			(end 0.12065 -0.2794)
			(stroke
				(width 0.1)
				(type default)
			)
			(layer "B.Fab")
		)
		(fp_line
			(start -0.120396 0.3048)
			(end -0.120396 0.2794)
			(stroke
				(width 0.1)
				(type default)
			)
			(layer "B.Fab")
		)
		(fp_line
			(start -0.120396 0.2794)
			(end 0.12065 0.2794)
			(stroke
				(width 0.1)
				(type default)
			)
			(layer "B.Fab")
		)
		(fp_line
			(start -0.12065 -0.2794)
			(end -0.12065 -0.3048)
			(stroke
				(width 0.1)
				(type default)
			)
			(layer "B.Fab")
		)
		(fp_line
			(start -0.12065 -0.3048)
			(end -0.67945 -0.3048)
			(stroke
				(width 0.1)
				(type default)
			)
			(layer "B.Fab")
		)
		(fp_line
			(start -0.67945 0.3048)
			(end -0.120396 0.3048)
			(stroke
				(width 0.1)
				(type default)
			)
			(layer "B.Fab")
		)
		(fp_line
			(start -0.67945 -0.3048)
			(end -0.67945 0.3048)
			(stroke
				(width 0.1)
				(type default)
			)
			(layer "B.Fab")
		)
		(pad "1" smd circle
			(at 0.40005 0)
			(size 0 0)
			(layers "B.Cu" "B.Mask" "B.Paste")
			(net "PVDD18_S5_P1")
		)
		(pad "2" smd circle
			(at -0.40005 0)
			(size 0 0)
			(layers "B.Cu" "B.Mask" "B.Paste")
			(net "SVID_PVDDCR_CPU1_P1_SVTI")
		)
	)
	(footprint ""
		(layer "B.Cu")
		(at 184.332372 -118.242842 90)
		(property "Reference" "C1132"
			(at 0 0 90)
			(layer "B.SilkS")
			(hide yes)
			(effects
				(font
					(size 1.27 1.27)
				)
				(justify mirror)
			)
		)
		(property "Value" ""
			(at 0 0 90)
			(layer "B.Fab")
			(effects
				(font
					(size 1.27 1.27)
				)
				(justify mirror)
			)
		)
		(duplicate_pad_numbers_are_jumpers no)
		(fp_line
			(start 0.69215 -0.2921)
			(end -0.69215 -0.2921)
			(stroke
				(width 0.1524)
				(type default)
			)
			(layer "B.SilkS")
		)
		(fp_line
			(start -0.69215 -0.2921)
			(end -0.69215 0.2921)
			(stroke
				(width 0.1524)
				(type default)
			)
			(layer "B.SilkS")
		)
		(fp_line
			(start 0.69215 0.2921)
			(end 0.69215 -0.2921)
			(stroke
				(width 0.1524)
				(type default)
			)
			(layer "B.SilkS")
		)
		(fp_line
			(start -0.69215 0.2921)
			(end 0.69215 0.2921)
			(stroke
				(width 0.1524)
				(type default)
			)
			(layer "B.SilkS")
		)
		(fp_line
			(start 0.51435 -0.2794)
			(end -0.51435 -0.2794)
			(stroke
				(width 0.1)
				(type default)
			)
			(layer "B.Fab")
		)
		(fp_line
			(start -0.51435 -0.2794)
			(end -0.51435 0.2794)
			(stroke
				(width 0.1)
				(type default)
			)
			(layer "B.Fab")
		)
		(fp_line
			(start 0.51435 0.2794)
			(end 0.51435 -0.2794)
			(stroke
				(width 0.1)
				(type default)
			)
			(layer "B.Fab")
		)
		(fp_line
			(start -0.51435 0.2794)
			(end 0.51435 0.2794)
			(stroke
				(width 0.1)
				(type default)
			)
			(layer "B.Fab")
		)
		(pad "1" smd circle
			(at 0.40005 0 270)
			(size 0 0)
			(layers "B.Cu" "B.Mask" "B.Paste")
			(net "P1V8_AUX")
		)
		(pad "2" smd circle
			(at -0.40005 0 270)
			(size 0 0)
			(layers "B.Cu" "B.Mask" "B.Paste")
			(net "GND")
		)
		(zone
			(layer "B.Cu")
			(hatch none 0.5)
			(connect_pads
				(clearance 0)
			)
			(min_thickness 0.25)
			(keepout
				(tracks not_allowed)
				(vias allowed)
				(pads allowed)
				(copperpour not_allowed)
				(footprints allowed)
			)
			(placement
				(enabled no)
				(sheetname "")
			)
			(fill
				(thermal_gap 0.5)
				(thermal_bridge_width 0.5)
				(island_removal_mode 0)
			)
			(polygon
				(pts
					(xy 184.186322 -118.142512) (xy 184.186322 -118.341902) (xy 184.244488 -118.433342) (xy 184.420002 -118.433342)
					(xy 184.478168 -118.341902) (xy 184.478168 -118.142512) (xy 184.420002 -118.052342) (xy 184.244742 -118.052342)
				)
			)
		)
	)
)
